(kicad_pcb
	(version 20241229)
	(generator "pcbnew")
	(generator_version "9.0")
	(general
		(thickness 1.62)
		(legacy_teardrops no)
	)
	(paper "A3")
	(title_block
		(title "COM Express 7 Baseboard")
		(date "2025-02-04")
		(rev "1.1.2")
		(company "Antmicro Ltd")
		(comment 1 "www.antmicro.com")
		(comment 9 "footprints 228-232 of 802")
	)
	(layers
		(0 "F.Cu" signal)
		(4 "In1.Cu" signal)
		(6 "In2.Cu" signal)
		(8 "In3.Cu" signal)
		(10 "In4.Cu" signal)
		(12 "In5.Cu" signal)
		(14 "In6.Cu" signal)
		(2 "B.Cu" signal)
		(9 "F.Adhes" user "F.Adhesive")
		(11 "B.Adhes" user "B.Adhesive")
		(13 "F.Paste" user)
		(15 "B.Paste" user)
		(5 "F.SilkS" user "F.Silkscreen")
		(7 "B.SilkS" user "B.Silkscreen")
		(1 "F.Mask" user)
		(3 "B.Mask" user)
		(17 "Dwgs.User" user "User.Drawings")
		(19 "Cmts.User" user "User.Comments")
		(21 "Eco1.User" user "User.Eco1")
		(23 "Eco2.User" user "User.Eco2")
		(25 "Edge.Cuts" user)
		(27 "Margin" user)
		(31 "F.CrtYd" user "F.Courtyard")
		(29 "B.CrtYd" user "B.Courtyard")
		(35 "F.Fab" user)
		(33 "B.Fab" user)
	)
	(footprint "antmicro-footprints:R_0402_1005Metric"
		(layer "F.Cu")
		(at 202 160)
		(descr "Resistor SMD 0402")
		(tags "resistor SMD 0402")
		(property "Reference" "R158"
			(at 1 0.4 0)
			(layer "F.SilkS")
			(effects
				(font
					(size 0.7 0.7)
					(thickness 0.15)
				)
				(justify left bottom)
			)
		)
		(property "Value" "R_10k_0402"
			(at -4.236843 54.437047 0)
			(layer "F.Fab")
			(hide yes)
			(effects
				(font
					(size 0.7 0.7)
					(thickness 0.15)
				)
				(justify left bottom)
			)
		)
		(property "Datasheet" "https://www.bourns.com/docs/product-datasheets/cr.pdf"
			(at 0 0 0)
			(layer "F.Fab")
			(hide yes)
			(effects
				(font
					(size 1.27 1.27)
					(thickness 0.15)
				)
			)
		)
		(property "Author" "Antmicro"
			(at 0 0 0)
			(layer "F.Fab")
			(hide yes)
			(effects
				(font
					(size 1 1)
					(thickness 0.15)
				)
			)
		)
		(property "License" "Apache-2.0"
			(at 0 0 0)
			(layer "F.Fab")
			(hide yes)
			(effects
				(font
					(size 1 1)
					(thickness 0.15)
				)
			)
		)
		(property "MPN" "CR0402-FX-1002GLF"
			(at 0 0 0)
			(layer "F.Fab")
			(hide yes)
			(effects
				(font
					(size 1 1)
					(thickness 0.15)
				)
			)
		)
		(property "Manufacturer" "Bourns"
			(at 0 0 0)
			(layer "F.Fab")
			(hide yes)
			(effects
				(font
					(size 1 1)
					(thickness 0.15)
				)
			)
		)
		(property "Public" "False"
			(at 0 0 0)
			(layer "F.Fab")
			(hide yes)
			(effects
				(font
					(size 1 1)
					(thickness 0.15)
				)
			)
		)
		(property "Tolerance" "1%"
			(at 0 0 0)
			(layer "F.Fab")
			(hide yes)
			(effects
				(font
					(size 1 1)
					(thickness 0.15)
				)
			)
		)
		(property "Val" "10k"
			(at 0 0 0)
			(layer "F.Fab")
			(hide yes)
			(effects
				(font
					(size 1 1)
					(thickness 0.15)
				)
			)
		)
		(sheetname "Com Express 7 Interfaces")
		(sheetfile "com_express_7_interfaces.kicad_sch")
		(attr smd)
		(fp_rect
			(start -0.925 -0.47)
			(end 0.925 0.47)
			(stroke
				(width 0.05)
				(type default)
			)
			(fill no)
			(layer "F.CrtYd")
		)
		(fp_rect
			(start -0.5 -0.25)
			(end 0.5 0.25)
			(stroke
				(width 0.15)
				(type solid)
			)
			(fill no)
			(layer "F.Fab")
		)
		(pad "1" smd roundrect
			(at -0.48 0)
			(size 0.59 0.64)
			(layers "F.Cu" "F.Mask" "F.Paste")
			(roundrect_rratio 0.25)
			(net 1 "GND")
			(pintype "passive")
			(teardrops
				(best_length_ratio 0.2)
				(max_length 1)
				(best_width_ratio 0.9)
				(max_width 2)
				(curved_edges yes)
				(filter_ratio 0.9)
				(enabled yes)
				(allow_two_segments yes)
				(prefer_zone_connections yes)
			)
		)
		(pad "2" smd roundrect
			(at 0.48 0)
			(size 0.59 0.64)
			(layers "F.Cu" "F.Mask" "F.Paste")
			(roundrect_rratio 0.25)
			(net 386 "/Com Express 7 Interfaces/SD_WP")
			(pintype "passive")
			(teardrops
				(best_length_ratio 0.2)
				(max_length 1)
				(best_width_ratio 0.9)
				(max_width 2)
				(curved_edges yes)
				(filter_ratio 0.9)
				(enabled yes)
				(allow_two_segments yes)
				(prefer_zone_connections yes)
			)
		)
	)
	(footprint "antmicro-footprints:R_0402_1005Metric"
		(layer "F.Cu")
		(at 255.975 132.36 90)
		(descr "Resistor SMD 0402")
		(tags "resistor SMD 0402")
		(property "Reference" "R169"
			(at -3.65 0.425 90)
			(layer "F.SilkS")
			(effects
				(font
					(size 0.7 0.7)
					(thickness 0.15)
				)
				(justify left bottom)
			)
		)
		(property "Value" "R_10k_0402"
			(at -1.011843 1.772047 90)
			(layer "F.Fab")
			(effects
				(font
					(size 0.7 0.7)
					(thickness 0.15)
				)
				(justify left bottom)
			)
		)
		(property "Datasheet" "https://www.bourns.com/docs/product-datasheets/cr.pdf"
			(at 0 0 90)
			(layer "F.Fab")
			(hide yes)
			(effects
				(font
					(size 1.27 1.27)
					(thickness 0.15)
				)
			)
		)
		(property "Author" "Antmicro"
			(at 388.335 -123.615 0)
			(layer "F.Fab")
			(hide yes)
			(effects
				(font
					(size 1 1)
					(thickness 0.15)
				)
			)
		)
		(property "License" "Apache-2.0"
			(at 388.335 -123.615 0)
			(layer "F.Fab")
			(hide yes)
			(effects
				(font
					(size 1 1)
					(thickness 0.15)
				)
			)
		)
		(property "MPN" "CR0402-FX-1002GLF"
			(at 388.335 -123.615 0)
			(layer "F.Fab")
			(hide yes)
			(effects
				(font
					(size 1 1)
					(thickness 0.15)
				)
			)
		)
		(property "Manufacturer" "Bourns"
			(at 388.335 -123.615 0)
			(layer "F.Fab")
			(hide yes)
			(effects
				(font
					(size 1 1)
					(thickness 0.15)
				)
			)
		)
		(property "Public" "False"
			(at 388.335 -123.615 0)
			(layer "F.Fab")
			(hide yes)
			(effects
				(font
					(size 1 1)
					(thickness 0.15)
				)
			)
		)
		(property "Tolerance" "1%"
			(at 388.335 -123.615 0)
			(layer "F.Fab")
			(hide yes)
			(effects
				(font
					(size 1 1)
					(thickness 0.15)
				)
			)
		)
		(property "Val" "10k"
			(at 388.335 -123.615 0)
			(layer "F.Fab")
			(hide yes)
			(effects
				(font
					(size 1 1)
					(thickness 0.15)
				)
			)
		)
		(sheetname "Com Express 7 MGMT")
		(sheetfile "com_express_7_mgmt.kicad_sch")
		(attr smd)
		(fp_rect
			(start -0.925 -0.47)
			(end 0.925 0.47)
			(stroke
				(width 0.05)
				(type default)
			)
			(fill no)
			(layer "F.CrtYd")
		)
		(fp_rect
			(start -0.5 -0.25)
			(end 0.5 0.25)
			(stroke
				(width 0.15)
				(type solid)
			)
			(fill no)
			(layer "F.Fab")
		)
		(pad "1" smd roundrect
			(at -0.48 0 90)
			(size 0.59 0.64)
			(layers "F.Cu" "F.Mask" "F.Paste")
			(roundrect_rratio 0.25)
			(net 137 "/Com Express 7 MGMT/~{TYPE2}")
			(pintype "passive")
			(teardrops
				(best_length_ratio 0.2)
				(max_length 1)
				(best_width_ratio 0.9)
				(max_width 2)
				(curved_edges yes)
				(filter_ratio 0.9)
				(enabled yes)
				(allow_two_segments yes)
				(prefer_zone_connections yes)
			)
		)
		(pad "2" smd roundrect
			(at 0.48 0 90)
			(size 0.59 0.64)
			(layers "F.Cu" "F.Mask" "F.Paste")
			(roundrect_rratio 0.25)
			(net 73 "+3V3_AON")
			(pintype "passive")
			(teardrops
				(best_length_ratio 0.2)
				(max_length 1)
				(best_width_ratio 0.9)
				(max_width 2)
				(curved_edges yes)
				(filter_ratio 0.9)
				(enabled yes)
				(allow_two_segments yes)
				(prefer_zone_connections yes)
			)
		)
	)
	(footprint "antmicro-footprints:R_0402_1005Metric"
		(layer "F.Cu")
		(at 126.425 86.060001 180)
		(descr "Resistor SMD 0402")
		(tags "resistor SMD 0402")
		(property "Reference" "R241"
			(at -1.575 -6.4 0)
			(layer "F.SilkS")
			(effects
				(font
					(size 0.7 0.7)
					(thickness 0.15)
				)
				(justify right bottom)
			)
		)
		(property "Value" "R_0R_0402"
			(at -1.011843 1.772047 0)
			(layer "F.Fab")
			(effects
				(font
					(size 0.7 0.7)
					(thickness 0.15)
				)
				(justify right bottom)
			)
		)
		(property "Datasheet" "https://industrial.panasonic.com/cdbs/www-data/pdf/RDA0000/AOA0000C301.pdf"
			(at 0 0 180)
			(layer "F.Fab")
			(hide yes)
			(effects
				(font
					(size 1.27 1.27)
					(thickness 0.15)
				)
			)
		)
		(property "Author" "Antmicro"
			(at 252.85 172.120002 0)
			(layer "F.Fab")
			(hide yes)
			(effects
				(font
					(size 1 1)
					(thickness 0.15)
				)
			)
		)
		(property "Current" "1A"
			(at 252.85 172.120002 0)
			(layer "F.Fab")
			(hide yes)
			(effects
				(font
					(size 1 1)
					(thickness 0.15)
				)
			)
		)
		(property "License" "Apache-2.0"
			(at 252.85 172.120002 0)
			(layer "F.Fab")
			(hide yes)
			(effects
				(font
					(size 1 1)
					(thickness 0.15)
				)
			)
		)
		(property "MPN" "ERJ2GE0R00X"
			(at 252.85 172.120002 0)
			(layer "F.Fab")
			(hide yes)
			(effects
				(font
					(size 1 1)
					(thickness 0.15)
				)
			)
		)
		(property "Manufacturer" "Panasonic"
			(at 252.85 172.120002 0)
			(layer "F.Fab")
			(hide yes)
			(effects
				(font
					(size 1 1)
					(thickness 0.15)
				)
			)
		)
		(property "Public" "False"
			(at 252.85 172.120002 0)
			(layer "F.Fab")
			(hide yes)
			(effects
				(font
					(size 1 1)
					(thickness 0.15)
				)
			)
		)
		(property "Tolerance" ""
			(at 252.85 172.120002 0)
			(layer "F.Fab")
			(hide yes)
			(effects
				(font
					(size 1 1)
					(thickness 0.15)
				)
			)
		)
		(property "Val" "0R"
			(at 252.85 172.120002 0)
			(layer "F.Fab")
			(hide yes)
			(effects
				(font
					(size 1 1)
					(thickness 0.15)
				)
			)
		)
		(sheetname "GPIO expander")
		(sheetfile "gpio_exp.kicad_sch")
		(attr smd)
		(fp_rect
			(start -0.925 -0.47)
			(end 0.925 0.47)
			(stroke
				(width 0.05)
				(type default)
			)
			(fill no)
			(layer "F.CrtYd")
		)
		(fp_rect
			(start -0.5 -0.25)
			(end 0.5 0.25)
			(stroke
				(width 0.15)
				(type solid)
			)
			(fill no)
			(layer "F.Fab")
		)
		(pad "1" smd roundrect
			(at -0.48 0 180)
			(size 0.59 0.64)
			(layers "F.Cu" "F.Mask" "F.Paste")
			(roundrect_rratio 0.25)
			(net 642 "Net-(U41-IO0_3)")
			(pintype "passive")
			(teardrops
				(best_length_ratio 0.2)
				(max_length 1)
				(best_width_ratio 0.9)
				(max_width 2)
				(curved_edges yes)
				(filter_ratio 0.9)
				(enabled yes)
				(allow_two_segments yes)
				(prefer_zone_connections yes)
			)
		)
		(pad "2" smd roundrect
			(at 0.48 0 180)
			(size 0.59 0.64)
			(layers "F.Cu" "F.Mask" "F.Paste")
			(roundrect_rratio 0.25)
			(net 941 "/2xUSB3.0+RJ45/EN_1")
			(pintype "passive")
			(teardrops
				(best_length_ratio 0.2)
				(max_length 1)
				(best_width_ratio 0.9)
				(max_width 2)
				(curved_edges yes)
				(filter_ratio 0.9)
				(enabled yes)
				(allow_two_segments yes)
				(prefer_zone_connections yes)
			)
		)
	)
	(footprint "antmicro-footprints:R_0402_1005Metric"
		(layer "F.Cu")
		(at 123.38 75.81 -90)
		(descr "Resistor SMD 0402")
		(tags "resistor SMD 0402")
		(property "Reference" "R75"
			(at -3 -0.45 90)
			(layer "F.SilkS")
			(effects
				(font
					(size 0.7 0.7)
					(thickness 0.15)
				)
				(justify right bottom)
			)
		)
		(property "Value" "R_0R_0402"
			(at -1.011843 1.772047 90)
			(layer "F.Fab")
			(effects
				(font
					(size 0.7 0.7)
					(thickness 0.15)
				)
				(justify right bottom)
			)
		)
		(property "Datasheet" "https://industrial.panasonic.com/cdbs/www-data/pdf/RDA0000/AOA0000C301.pdf"
			(at 0 0 270)
			(layer "F.Fab")
			(hide yes)
			(effects
				(font
					(size 1.27 1.27)
					(thickness 0.15)
				)
			)
		)
		(property "Author" "Antmicro"
			(at 47.57 199.19 0)
			(layer "F.Fab")
			(hide yes)
			(effects
				(font
					(size 1 1)
					(thickness 0.15)
				)
			)
		)
		(property "Current" "1A"
			(at 47.57 199.19 0)
			(layer "F.Fab")
			(hide yes)
			(effects
				(font
					(size 1 1)
					(thickness 0.15)
				)
			)
		)
		(property "License" "Apache-2.0"
			(at 47.57 199.19 0)
			(layer "F.Fab")
			(hide yes)
			(effects
				(font
					(size 1 1)
					(thickness 0.15)
				)
			)
		)
		(property "MPN" "ERJ2GE0R00X"
			(at 47.57 199.19 0)
			(layer "F.Fab")
			(hide yes)
			(effects
				(font
					(size 1 1)
					(thickness 0.15)
				)
			)
		)
		(property "Manufacturer" "Panasonic"
			(at 47.57 199.19 0)
			(layer "F.Fab")
			(hide yes)
			(effects
				(font
					(size 1 1)
					(thickness 0.15)
				)
			)
		)
		(property "Public" "False"
			(at 47.57 199.19 0)
			(layer "F.Fab")
			(hide yes)
			(effects
				(font
					(size 1 1)
					(thickness 0.15)
				)
			)
		)
		(property "Tolerance" ""
			(at 47.57 199.19 0)
			(layer "F.Fab")
			(hide yes)
			(effects
				(font
					(size 1 1)
					(thickness 0.15)
				)
			)
		)
		(property "Val" "0R"
			(at 47.57 199.19 0)
			(layer "F.Fab")
			(hide yes)
			(effects
				(font
					(size 1 1)
					(thickness 0.15)
				)
			)
		)
		(sheetname "USB-C console")
		(sheetfile "usb-c_console.kicad_sch")
		(attr smd)
		(fp_rect
			(start -0.925 -0.47)
			(end 0.925 0.47)
			(stroke
				(width 0.05)
				(type default)
			)
			(fill no)
			(layer "F.CrtYd")
		)
		(fp_rect
			(start -0.5 -0.25)
			(end 0.5 0.25)
			(stroke
				(width 0.15)
				(type solid)
			)
			(fill no)
			(layer "F.Fab")
		)
		(pad "1" smd roundrect
			(at -0.48 0 270)
			(size 0.59 0.64)
			(layers "F.Cu" "F.Mask" "F.Paste")
			(roundrect_rratio 0.25)
			(net 572 "Net-(U7-A_{2})")
			(pintype "passive")
			(teardrops
				(best_length_ratio 0.2)
				(max_length 1)
				(best_width_ratio 0.9)
				(max_width 2)
				(curved_edges yes)
				(filter_ratio 0.9)
				(enabled yes)
				(allow_two_segments yes)
				(prefer_zone_connections yes)
			)
		)
		(pad "2" smd roundrect
			(at 0.48 0 270)
			(size 0.59 0.64)
			(layers "F.Cu" "F.Mask" "F.Paste")
			(roundrect_rratio 0.25)
			(net 345 "/Com Express 7 MGMT/SER0.RX")
			(pintype "passive")
			(teardrops
				(best_length_ratio 0.2)
				(max_length 1)
				(best_width_ratio 0.9)
				(max_width 2)
				(curved_edges yes)
				(filter_ratio 0.9)
				(enabled yes)
				(allow_two_segments yes)
				(prefer_zone_connections yes)
			)
		)
	)
	(footprint "antmicro-footprints:TP_SMD_0.75mm"
		(layer "F.Cu")
		(at 129.09 129.56)
		(property "Reference" "TP96"
			(at 0.46 -1.25 90)
			(layer "F.SilkS")
			(effects
				(font
					(size 0.7 0.7)
					(thickness 0.15)
				)
				(justify left bottom)
			)
		)
		(property "Value" "TP_0.75mm_SMD"
			(at 0 1.2 0)
			(layer "F.Fab")
			(effects
				(font
					(size 0.7 0.7)
					(thickness 0.15)
				)
				(justify left bottom)
			)
		)
		(property "Author" "Antmicro"
			(at 0 0 0)
			(layer "F.Fab")
			(hide yes)
			(effects
				(font
					(size 1 1)
					(thickness 0.15)
				)
			)
		)
		(property "License" "Apache-2.0"
			(at 0 0 0)
			(layer "F.Fab")
			(hide yes)
			(effects
				(font
					(size 1 1)
					(thickness 0.15)
				)
			)
		)
		(property "MPN" ""
			(at 0 0 0)
			(layer "F.Fab")
			(hide yes)
			(effects
				(font
					(size 1 1)
					(thickness 0.15)
				)
			)
		)
		(property "Manufacturer" ""
			(at 0 0 0)
			(layer "F.Fab")
			(hide yes)
			(effects
				(font
					(size 1 1)
					(thickness 0.15)
				)
			)
		)
		(property "Public" "False"
			(at 0 0 0)
			(layer "F.Fab")
			(hide yes)
			(effects
				(font
					(size 1 1)
					(thickness 0.15)
				)
			)
		)
		(sheetname "KR to SFI #2")
		(sheetfile "kr_sfi.kicad_sch")
		(attr exclude_from_pos_files exclude_from_bom)
		(fp_circle
			(center 0 0)
			(end 0.475 0)
			(stroke
				(width 0.05)
				(type default)
			)
			(fill no)
			(layer "F.CrtYd")
		)
		(pad "1" smd circle
			(at 0 0)
			(size 0.75 0.75)
			(layers "F.Cu" "F.Mask")
			(net 759 "Net-(U45B-LS_OK_{OUT_B})")
			(pinfunction "1")
			(pintype "passive")
			(teardrops
				(best_length_ratio 0.4)
				(max_length 1)
				(best_width_ratio 0.9)
				(max_width 2)
				(curved_edges yes)
				(filter_ratio 0.9)
				(enabled yes)
				(allow_two_segments yes)
				(prefer_zone_connections yes)
			)
		)
	)
)
